 
 
Open CloudServer  
blade specification   
V1.0 
 
Authors: 
Mark Shaw, Director of Hardware Engineering, Microsoft 
Martin Goldstein, Principal Systems Architect, Microsoft 
  


 
2 January 28, 2014 
1 Revision History 
 
Date Name Description 
1/28/2014  Version 1.0 
   
   
   
   
   
   
   
 
 
 
 
  



Open Compute Project  Open CloudServer blade specification 
http://opencompute.org 3 
© 2014 Microsoft Corporation. 
 
As of January 28, 2014, the following persons or entities have made this Specification available under 
the Open Web Foundation Final Specification Agreement (OWFa 1.0), which is available at 
http://www.openwebfoundation.org/legal/the-owf-1-0-agreements/owfa-1-0 Microsoft Corporation.  
You can review the signed copies of the Open Web Foundation Agreement Version 1.0 for this 
Specification at http://opencompute.org/licensing/, which may also include additional parties to those 
listed above. 
Your use of this Specification may be subject to other third party rights. THIS SPECIFICATION IS 
PROVIDED "AS IS." The contributors expressly disclaim any warranties (express, implied, or otherwise), 
including implied warranties of merchantability, noninfringement, fitness for a particular purpose, or title, 
related to the Specification. The entire risk as to implementing or otherwise using the Specification is 
assumed by the Specification implementer and user. IN NO EVENT WILL ANY PARTY BE LIABLE TO ANY 
OTHER PARTY FOR LOST PROFITS OR ANY FORM OF INDIRECT, SPECIAL, INCIDENTAL, OR 
CONSEQUENTIAL DAMAGES OF ANY CHARACTER FROM ANY CAUSES OF ACTION OF ANY KIND WITH 
RESPECT TO THIS SPECIFICATION OR ITS GOVERNING AGREEMENT, WHETHER BASED ON BREACH OF 
CONTRACT, TORT (INCLUDING NEGLIGENCE), OR OTHERWISE, AND WHETHER OR NOT THE OTHER 
PARTY HAS BEEN ADVISED OF THE POSSIBILITY OF SUCH DAMAGE. 
CONTRIBUTORS AND LICENSORS OF THIS SPECIFICATION MAY HAVE MENTIONED CERTAIN 
TECHNOLOGIES THAT ARE MERELY REFERENCED WITHIN THIS SPECIFICATION AND NOT LICENSED 
UNDER THE OWF CLA OR OWFa. THE FOLLOWING IS A LIST OF MERELY REFERENCED TECHNOLOGY: 
INTELLIGENT PLATFORM MANAGEMENT INTERFACE (IPMI), I2C TRADEMARK OF PHILLIPS 
SEMICONDUCTOR. IMPLEMENTATION OF THESE TECHNOLOGIES MAY BE SUBJECT TO THEIR OWN 
LEGAL TERMS.  



 
4 January 28, 2014 
2 Scope 
This document provides the technical specifications for the design of the Open 
CloudServer blade. 
3 Contents 
1 Revision History ......................................................................................................................... 2 
2 Scope ......................................................................................................................................... 4 
3 Contents .................................................................................................................................... 4 
4 Overview.................................................................................................................................... 6 
5 Software and Firmware Specification ....................................................................................... 6 
5.1 Operating System Version Requirements .................................................................... 7 
5.2 Certification Requirements .......................................................................................... 7 
5.3 Device Driver Requirements ........................................................................................ 7 
5.4 Firmware Requirements ............................................................................................... 8 
5.5 BIOS and UEFI Requirements ....................................................................................... 9 
5.6 BIOS Debug ................................................................................................................. 11 
5.7 BIOS Recovery ............................................................................................................ 11 
5.8 Event Log Requirements ............................................................................................ 12 
5.9 Network Systems Requirements ................................................................................ 13 
5.10 Storage Controller ...................................................................................................... 13 
6 Blade Physical Specifications ................................................................................................... 14 
6.1 Volumetric Specifications ........................................................................................... 14 
6.2 Weight and Structure ................................................................................................. 16 
6.3 Guiding and Latching Features ................................................................................... 16 
6.4 Electromagnetic Interference Mitigation ................................................................... 20 
7 Blade Interconnects ................................................................................................................. 20 
7.1 Power ......................................................................................................................... 22 
7.2 Signal Interface ........................................................................................................... 26 
8 Mezzanine I/O ......................................................................................................................... 33 
9 PCI-Express Expansion Slot ...................................................................................................... 33 
10 Blade Management ................................................................................................................. 37 



Open Compute Project  Open CloudServer blade specification 
http://opencompute.org 5 
10.1 Overview of Blade Management ................................................................................ 37 
10.2 Blade LEDs .................................................................................................................. 39 
11 Appendix: Commonly Used Acronyms .................................................................................... 42 
  



 
6 January 28, 2014 
4 Overview 
The Open CloudServer blades are highly configurable, and are usually compute 
blades or storage “just a bunch of disks” (JBOD) blades. Figure 1 shows an example 
of a compute blade. 
 
Figure 1. Compute blade 
Power, management, and networking signals are delivered to the blade through 
blind-mate connectors to the tray backplane (TB). Networking and storage signals are 
routed to attachments on the TB at the rear of the chassis, enabling service without 
touching cables. 
5 Software and Firmware Specification 
The following sections define the software/firmware requirements a server must meet 
to be deployable in cloud-scale environments. These requirements are targeted for 
supplier partners. 


Open Compute Project  Open CloudServer blade specification 
http://opencompute.org 7 
5.1 Operating System Version Requirements 
Any reference to an operating system in this specification refers to the Windows 
Server operating system. Unless otherwise specified, “Windows” refers to the 
Windows Server 2012 operating system (or later versions). The term “driver” refers to 
the Windows Server device driver. Note that the only supported version of Windows 
Server is x64. 
Windows Preinstallation Environment (Windows PE) is not used for production; 
however, it is used for operating system deployment (imaging), for recovery, and for 
some specific maintenance/manageability scenarios (for example, for issuing secure 
erase on hard-disk drives [HDDs] and solid-state drives [SSDs]). For this reason, 
Windows PE 4.0 (64-bit versions) should boot on the server, and all devices should 
be accessible after Windows PE boots. 
5.2 Certification Requirements 
The server and any associated devices must pass the Windows Hardware Certification 
program tests. The most recent Windows Hardware Certification Kit (HCK) should be 
used unless otherwise specified.  
If the server fails to pass certain tests because of required hardware design tradeoffs, 
failures must be documented and approved by <name> and 
Integration team. 
5.3 Device Driver Requirements 
Table 1 lists the requirements that all device and device-driver updates should meet.  
Table 1. Device Driver Requirements 
Device driver and driver update requirements 
 Support x64 versions of Windows Server 2012 (and later) and Windows PE 4.0 (or later) 
 Pass Windows Hardware Certification (must be signed) 
 Support silent option to allow for unattended (automated) installation 
 Have consistent return codes across all operating system versions 
 Include symbols (.pdb files) for debugging purposes  
 Driver update package should be accompanied by a detailed list of all bugs fixed 



 
8 January 28, 2014 
Device driver and driver update requirements 
 Driver updates should meet and pass all performance and functional tests 
 Driver upgrade tools should run on x64 versions of Windows Server 2012 (or later), and 
Windows PE 4.0 (or later) 
 Driver upgrade tools should be scriptable and support silent install mode (to support 
automated install/upgrade mode) 
 Driver upgrade tools should include version checking to prevent older-version drivers from 
being installed in place of newer drivers 
 Driver upgrade tools should support automation from Perl or Visual Basic Scripting Edition 
(VBScript) for automated upgrade and install operations 
 Install/upgrade tools should provide detailed logging information to help identify 
install/upgrade failures 
 Include dedicated path/secure location for driver packages (can be an file transfer protocol 
[FTP] or website); location should be refreshed regularly during every release period 
 Driver updates should be shipped a regular and predictable release plan  
 Driver update tool should use a fixed path for the error log 
 Driver updates should maintain the plug-and play (PNP) ID numbers 
5.4 Firmware Requirements 
Table 2 lists the requirements that all firmware and firmware updates, including basic 
input/output system (BIOS) and unified extensible firmware interface (UEFI), should 
meet. 
Table 2. Firmware Requirements 
Firmware and firmware update requirements 
 Support x64 versions of Windows Server 2012 (and later) and Windows PE 4.0 (and later) 
 Support silent option to allow for unattended (automated) install 
 Have consistent return codes across all operating system versions 
 Firmware update package should be accompanied by a detailed list of all bugs fixed 
 Meet and pass all related performance and functional tests 
 Firmware upgrade tools should run on x64 versions of Windows Server 2012 (and later) and 
Windows PE 4.0 (and later) 
 Firmware upgrade tools should have version checking to prevent older-version drivers from 
being installed in place of newer drivers 



Open Compute Project  Open CloudServer blade specification 
http://opencompute.org 9 
Firmware and firmware update requirements 
 Firmware upgrade tools should be scriptable and support silent install mode to support 
automated install/upgrade mode 
 Firmware upgrade tools should support automation from Perl or VBScript for automated 
upgrade and install operations. 
 Firmware upgrade tools should provide detailed logging information to help identify 
install/upgrade failures 
 Include dedicated path/secure location for firmware packages (can be FTP or website); 
location should be refreshed regularly during every release period 
 Firmware updates should be shipped a regular and predictable release plan 
 Firmware update tool should use a fixed path for the error log 
 Firmware updates should maintain the plug and play (PNP) ID numbers 
5.5  BIOS and UEFI Requirements 
The BIOS and UEFI are provided by the supplier. Table 3 lists the requirements that, 
in addition to those listed in Table 2, the BIOS and UEFI should meet. 
Table 3. BIOS and UEFI Requirements 
BIOS and UEFI requirements 
 BIOS/UEFI chip uses the PCH/ Wellsburg Platform Controller Hub (PCH) (Intel/AMD) serial 
peripheral interface (SPI)  
 16MB or higher is required 
 Supplier is responsible for selecting the BIOS chip that meets the required functionality  
 BIOS/UEFI source code is based on AMI Aptio 5.x reference BIOS for Intel Grantley CPU and 
Wellsburg PCH for the Mayan City reference motherboard I 
 Supplier is responsible for porting and maintaining the BIOS to make sure it has the latest 
version from AMI, AMD, or Intel 
 BIOS should have a setting to boot in native UEFI or UEFI/BIOS compatibility mode 
 UEFI/BIOS compatibility mode should be the default option 
 The BIOS should be tuned to minimize power consumption: 
o Disable unused devices such peripheral component interconnect express (PCIe) lanes, 
USB ports, and serial AT attachment (SATA)/ serial-attached SCSI (SAS) ports 
o Tune CPU/chipset settings to read the best power/performance mix 
o A modified SPECpower that takes disk I/O into account should be used as the 
benchmark for testing/validating the optimal power/performance settings 



 
10 January 28, 2014 
BIOS and UEFI requirements 
 BIOS/UEFI should expose the following settings: 
o Memory speed, Intel QuickPath Interconnect (QPI)/hyperthreading (HT) link speed, 
Speed-Step/Turbo mode, and CPU Cx power states 
o HT on/off 
o Enabling/disabling a socket or a core within a socket 
o Non-uniform memory access (NUMA) on/off switch 
o Advanced host controller interface (AHCI)/integrated development environment (IDE) 
mode switch 
o Implementation of a watchdog timer that is compatible with Windows Server (see 
http://msdn.microsoft.com/en-us/windows/hardware/gg463368.aspx)  
 Initial state should be “enabled/stopped” and the initial timeout value should be 
15 minutes  
 When the motherboard has a baseboard management controller (BMC), then the 
intelligent platform management interface (IPMI) watchdog timer should be used 
o Default power setting should be “power on” after power failure 
o BIOS/UEFI should implement a random delay for power on after power failure 
 The delay should be a random value ranging from 1 to 15 seconds 
 BIOS will provide enable/disable switch for this feature 
  If a BMC is available, then the delay should be implemented by the BMC; BIOS 
enable/disable switch will still control this BMC feature 
o Console redirection should be set to PCH/SP5100 virtual COM with baud rate 115200, 
no flow control, and terminal type VT100 
o Setting for error-correcting code (ECC) error threshold; available setting should be 1, 
4, 10, and 1000 
 If a complementary metal–oxide–semiconductor (CMOS) checksum errors occurs (during 
BIOS/UEFI update, for example), the BIOS/UEFI should load the system defaults automatically. 
 BIOS/UEFI settings and configuration tool should permit saving and updating the BIOS/UEFI 
settings to an XML or text configuration file 
 BIOS/UEFI should implement a BIOIS/UEFI recovery mechanism that can be used when a 
BIOS/UEFI upgrades fails 
 A recovery mechanism that used a USB storage device to recover the BIOS is highly 
recommended 
 BIOS should support Windows Hardware Error Architecture (WHEA) and complete WHEA 
memory structures. 



Open Compute Project  Open CloudServer blade specification 
http://opencompute.org 11 
5.6 BIOS Debug 
The blade contains a serial pin header on the main board for local serial console 
redirect. This functionality is in addition to the baseboard management controller 
(BMC) serial console redirect functionality. Serial console redirect should be capable 
of providing VT100 MRC debug, BIOS console debug, and Microsoft Windows EMS 
for host debug. 
5.7 BIOS Recovery 
The blade contains a USB connector for BIOS image recovery. When the BIOS is 
forced into recovery mode, it will automatically look for a recovery image on FAT32-
formatted USB media connected to the USB pins. 
The recovery process can be initiated by setting the recovery jumper. The BIOS will 
detect the recovery jumper set and start to execute the recovery code.  
The BIOS consists of three parts: the main BIOS section, the Non-volatile random-
access memory (NVRAM) section, and the boot block recovery section. The main 
BIOS section is updated during recovery process, but the NVRAM and the boot block 
sections are preserved. 
BIOS recovery is performed using the FAT32-formatted USB removable drive 
containing the BIOS image file (REC.ROM).  
Following is the recovery flow: 
1. Plug in the USB recovery media containing the file REC.ROM.  
2. Short the recovery jumper. 
3. Power on the system. 
4. The BIOS will automatically boot into the recovery page in BIOS the set up menu. 
5. Wait until recovery progress is complete. 
6. Set the recovery jumper back. 
7. Reboot the system with the new BIOS. 



 
12 January 28, 2014 
5.8 Event Log Requirements 
A hardware event log that keeps track of various system events and errors is 
required. This log is used for managing and diagnosing servers. Table 4 lists event 
log requirements. 
Table 4. Event Log Requirements 
Event log requirements 
 If a BMC is not available, the BIOS/UEFI is responsible for logging all events in a log 
compliant with systems management BIOS (SMBIOS) 2.6  
 If there is no hardware management device (HMD), BIOS/UEFI has to implement a log that is 
compliant with SMBIOS specification Rev 2.6 
 The log should hold at least 500 events and follow the SMBIOS event log organization format 
if an HMD is not present.  
 Each event record includes enhanced information identifying the error source device's vendor 
ID and device ID 
 In addition to being accessible through BIOS/UEFI, the supplier must provide a system access 
interface through the Windows Management Interface (WMI) 
 Driver should be compatible with 64-bit Windows Server 2012 (or a later version) 
 BIOS/UEFI, as well as the WMI interface, should allow for reading as well clearing the log 
 Logged errors should include: 
o CPU/memory errors: 
 Both correctable and uncorrectable ECC errors should be logged in the event log 
  Error categories include DRAM, Link, and L3 cache 
o QPI/HT link errors: 
 Any errors that have a status register should be logged into the event log 
o PCIe errors: 
 Any errors that have a status register should be logged into the event log, 
including root complex, endpoint device, and any switch upstream/downstream 
ports if available 
 Link disable on errors should also be logged 
 Fatal, non-fatal, or correctable classification follows the chipset vendor's 
recommendation 
o Power-on self-test (POST) errors: 
 All POST errors detected by the BIOS during POST are logged into the event log 
o Power errors; two power errors are logged: 
 12V DC input power failure that causes all power rails on motherboard to lose 
power including standby power 



Open Compute Project  Open CloudServer blade specification 
http://opencompute.org 13 
Event log requirements 
 Unexpected system shutdown during system S0/S1, while 12V DC input is still valid 
 An error threshold setting must be enabled for both correctable errors  
 Once the programmed threshold is reached, an event should be triggered and logged 
o Memory correctable ECC: 
 The default threshold value is 1000 
 When the threshold is reached, the BIOS should log the event including dual inline 
memory module (DIMM) location 
o QPI/HT Link errors: 
 Follow the chipset vendor's suggestion 
o PCIe errors: 
 Follow the chipset vendor's suggestion 
5.9 Network Systems Requirements 
Table 5 lists the systems requirements the network must meet, in addition to the 
requirements for device drivers listed in Table 1. Application specific requirements 
will be provided as needed during networking card development. 
Table 5. Network Systems Requirements 
Network systems requirements 
 Any firmware or driver upgrade should keep all static IP configurations to prevent the 
server from going offline after the upgrade 
 If multiple network interface cards (NICs) are present, they should PXE boot capable; by 
default, NIC 1 should be the network (PXE) NIC 
 Any firmware or driver upgrade should maintain NIC team configuration if present 
5.10 Storage Controller 
If used, a storage controller must meet the requirements listed in Table 6 and those 
for firmware listed in Table 2.   
Table 6. Storage Controller Requirements 
Storage controller update requirements 
 Storage controller settings and configuration tool should allow for saving the firmware 
settings to a TXT, INI, or XML configuration file 
 Redundant array of independent disks (RAID) set information should be included in the 



 
14 January 28, 2014 
output (such as RAID configuration, drives, and sizes) 
 Storage controller settings and Configuration Tool should allow for updating the firmware 
settings from a XML or text configuration file 
 Storage controller should provide a command line-interface to allow for an automated 
configuration 
 Storage controller should support secure erase on individual disks 
6 Blade Physical Specifications 
The physical specifications for the blades include the dimensions of the space into 
which the blade is installed, the blade weight limits, a description of the guiding and 
latching features, and information about electromagnetic interference (EMI) shielding. 
6.1 Volumetric Specifications 
The outer surfaces of the blade must fit into the volume defined in Figure 2, with all 
tolerances and manufacturing methods accounted for. No features of the blade 
(including the latch and the handle) can extend beyond the specified distance from 
the front column of the rack so that the front door of the rack can be closed without 
interference.  
This specification assumes a coplanar power/network distribution printed circuit 
board (PCB); if another structure is used, the connectors need to be form, fit, and 
functionally compatible with this specification. Note that if necessary, an EMI 
enclosure can be built to fit within the volumetric restrictions.  



Open Compute Project  Open CloudServer blade specification 
http://opencompute.org 15 
 
Figure 2. Dimensions of the volume that holds the blade 
Figure 3 shows the dimensions of the blade-mounting envelope, which holds the 
blade on the tray.  



 
16 January 28, 2014 
 
Figure 3. Blade-mounting envelope, front view 
Note that the only serviceable components in the blade are the hard drives, which 
can be replaced without tools. All other repairs to the blade are made in a bench-top 
environment. Components such as heat sinks, hard drives, and motherboards can be 
attached so that removal requires a tool, if this option is less expensive.  
6.2 Weight and Structure 
Because the tray can support a total weight of 50 pounds, a standard blade should 
not exceed a static weight of 25 pounds when loaded with all options.  
The blade must be mechanically stiff enough to support its own weight during 
shipping and handling. The side walls of the blade should be made as tall as possible 
within the given envelope to maximize the stiffness of the blade structure and allow 
for damage-free stacking during service. 
6.3 Guiding and Latching Features 
The following sections describe the guiding and latching features for the blade. 


Open Compute Project  Open CloudServer blade specification 
http://opencompute.org 17 
6.3.1 Latching Feature Identification 
Latches, as well as thumb screws and other components used to lock, unlock, or 
remove a subassembly from the chassis, are colored blue (Pantone code 285 C blue) 
to make them easy to identify.  
If the identity and function of a latching feature for a particular field replaceable unit 
(FRU) is clear, coloring might not be required. For example, a lock/unlock indicator is 
sufficient for a blade lever.  
6.3.2 Guiding and Latching 
Because a single tray design without a center rail is used for both half-width and full-
width blades, guides and alignment features are located in both the front and back 
of the enclosure. These features are especially important when inserting a half-width 
blade into an empty tray.  
The blade enclosure interfaces with the side walls of the tray and the guide pin in 
the tray to make sure the blade is aligned within the ±3.50mm (±0.138”) tolerance 
necessary to engage the connector. The guide pin in the tray aligns the half-width 
blades with the correct side of the tray. The blade connectors are protected from 
damage by the guide pin by the blade sheet metal. 
Figure 4 shows the blade guiding and latching features associated with the tray. 
Blade guide pins slide into slots on the front of the tray for alignment. A latch 
attached to the blade fits into a notch in the tray to secure the blade in place. 



 
18 January 28, 2014 
 
Figure 4. Guide and latch details, top view 
Figure 5 and Figure 6 show examples of a front-blade guide and latch and of a rear-
blade guide.  
Note that a lever is included at the front of the blade to provide additional guidance 
when the blade is locking into the tray, and to help with the force required to install 
and remove the blade from the tray. 



Open Compute Project  Open CloudServer blade specification 
http://opencompute.org 19 
  
Figure 5. Example of a front-blade guide and latch 
 
Figure 6. Example of a rear-blade guide pin 


 
20 January 28, 2014 
6.4 Electromagnetic Interference Mitigation 
For EMI containment, an EMI shield is added to the top rear edge of the tray, as 
shown in Figure 7.  
 
Figure 7. Tray with EMI enclosure, blade volume shown 
When all trays are in place, they are electrically stitched together to prevent leakage 
of electromagnetic fields. The blade also has a gasket on the front of the top surface 
that provides electrical sealing, as shown in Figure 8. Dimensions for this gasket are 
shown in Figure 2. 
 
Figure 8. Blade EMI seal 
7 Blade Interconnects 
The tray (or other supporting infrastructure) provides the electrical interface to the 
blade using the connectors listed in Table 7 (or their functional equivalents). Note 


Open Compute Project  Open CloudServer blade specification 
http://opencompute.org 21 
that the choice of these connectors is based on a coplanar PCB for power and 
network distribution.  
Table 7 lists the connectors used for mating the blade to the tray backplane. 
Table 7. Blade-to-Tray Backplane Connectors List 
Assembly 
mounting 
Assembly 
attachment Connector description  Manufacturing part number 
Blade Tray backplane Power header AirMax VS, 2x2 (FCI) 10028918-001LF 
Blade Tray backplane 
Signal connector—three pair, 
54 contact, 2mm spacing, 
17mm pitch, six column 
(FCI) 10039851-101LF 
Blade Tray backplane  Guide pin receptacle—10.8mm 
right angle, 0° key (FCI) 10037912-101LF 
Figure 9 shows the connector interface on the blade.  
 
 
Figure 9. Blade electrical connector interface 
Figure 10 shows the placement for the power and network distribution connectors. 


 
22 January 28, 2014 
 
Figure 10. Tray Backplane connector placement 
The total amount of force required to mate the blade to the tray backplane should 
not exceed 18.6 pounds throughout the expected service life of the connector set. 
With the leverage provided by the latch at the face of the blade, the force required 
should not exceed 3.15 pounds. The retention force of the connectors is a minimum 
of 5.66 pounds, which equates to 0.94 pounds minimum force at the latch. 
7.1 Power 
The sections that follow provide information about the power specifications for the 
blade.  
7.1.1 Power Connector 
The power connector used is in the FCI AirMax VS connector family.  
Figure 11 shows the power connector layout, and Table 8 shows the power 
receptacle pinout.  


Open Compute Project  Open CloudServer blade specification 
http://opencompute.org 23 
 
 
Figure 11. AirMax power receptacle pin out arrangement 
Table 8. Power Receptacle Pinout 
Pin Signal name Capacity (in A) 
Position 1 12V return – first mate 18A 
Position 2 12V supply 18A 
Position 4 12V supply 18A 
Position 3 12V return 18A 
The maximum power capacity for the blade with a single connector is 345W (12V x 2 
x 18A x 80 percent de-rating). Note that depending on the implementation, the 
maximum might not be achievable. 
7.1.2 Input Voltage, Power, and Current 
Table 9 lists the nominal, maximum, and minimum values for the blade input voltage. 
The maximum and minimum voltages include the effects of connector temperature, 
age, noise/ripple, and dynamic loading.  
Table 9. Input Voltage Range 
Nominal voltage Maximum voltage Minimum voltage 
12.25V DC 12.95V DC 11.65V DC 
 


 
24 January 28, 2014 
The maximum amount of power allowed per blade is defined during system power 
allocation. The number of blades in a chassis might be limited by the capacity of the 
AC power cord or by the cooling capacity of the deployment. Table 10 lists the input 
power allocation for a low-power blade. 
Table 10. Input Power Allocation and Maximum Current 
 
Nominal voltage System power allocation  
(in W) 
Maximum current  
(in A) 
Low-power blade 
(1x power connector) 
12.25VDC 300W 27.3A 
The blade provides in-rush current control through the 12V bus rail; return-side  
in-rush control is not used. The in-rush current rises linearly from 0A to the load 
current over a 5 millisecond (ms) period (this time period must be no longer than 
200ms).  
7.1.3 In-Rush Power Control Signals 
The sections that follow describe how the Blade_Enable (or Blade_EN) and 
Blade_Mated signals work. 
7.1.3.1 Blade Enable Signal 
The active high blade interrupts the 12Vbus when the Blade_EN[1..2] signal is toggled 
to ground. The Blade_EN signal driver from the chassis management card (CMC) is 
an open collector; in normal operation, it will be pulled high through a resistive 
termination when the blade is provided with 3.3V.  
To disable the power, the CMC pulls the Blade_EN signal to reference ground. The 
Blade_EN signal should not be pulled low on the blade and driven back to the 
Chassis Manager. 
7.1.3.2 Blade Mated Signal 
The active low Blade[1:2]_Mated_N signal is used to qualify Blade_EN to indicate that 
the connectors have properly mated during blade insertion before the 12V in-rush 
power is turned on. The mated signal is pulled to ground on the tray backplane 



Open Compute Project  Open CloudServer blade specification 
http://opencompute.org 25 
through a 100 ohm (Ω) resistor. It is pulled high through a resistive termination 
based on the incoming 12V on the blade.  
7.1.3.3 Interpretation of Signals 
Table 11 describes the Blade_EN and Blade_Mated signals.  
Table 11. Interpretation of Blade_EN and Blade_Mated Signals 
Blade_EN  
on blade 
Blade_Mated  
on blade Blade/hot swap controller status 
1 1 
During blade removal: 
 No 12V power, no signal connection to backplane 
 Blade was either not inserted or recently removed 
 Blade 12V should be DISABLED 
1 1 
During blade insertion: 
 Blade installation, 12V connector hits before signal 
 Signal connector is not mated 
 Hot swap controller is DISABLED 
1  0 
 Blade is installed, 12V is present 
 Signal connector is mated 
 Chassis Manager is either not present or is driving high 
 Hot swap controller is ENABLED 
0 1 
 Invalid or faulty state  
 The only way to drive Blade_Enable low is from the CM through 
the signal connector  
 If Blade_Mated is high, the connection was not made 
 Hot swap controller is DISABLED 
0 0 
 Blade is installed, 12V is present 
 Signal connector is mated 
 Chassis Manager drives Blade_Enable low 
 Hot swap controller is DISABLED 
7.1.4 Current Interrupt Protection and Power, Voltage, and Current Monitoring 
The blade provides a cost-effective way to measure and report blade voltage and 
current consumption, and to make instance reporting available to the system. The 
V1.0 blades include power consumption measurements at the in-rush controller. 



 
26 January 28, 2014 
(Accuracy of the measurement will be decided upon during the implementation of 
the design when costs are known.)  
The blade also provides a way to interrupt current flow within 1 microsecond (μs) of 
exceeding three times the maximum current load. 
7.1.5 Filtering and Capacitance 
The blade provides sufficient filtering to operate with a 0.25A/μSec DC source. 
Maximum capacitance allowed per blade is 12,000μFarads (μF). Minimum capacitance 
allowed per blade is 300μF. 
7.1.6 Grounding and Return 
The blade chassis grounding/return is provided by the assembly guide pin. The logic 
return, or 12V bus return, is provided through the 12V bus power connectors and 
signal connectors. The logic return and chassis return are not attached, bonded, or 
connected within the blade assembly.  
7.2 Signal Interface 
The sections that follow define the signaling interface to the blade. 
7.2.1 Signal Connectors 
The signal connector used is in the FCI AirMax VSe family. Figure 12 shows an 
example of coplanar connector pair. 
 
Figure 12. Example of a coplanar blade signal connector 


Open Compute Project  Open CloudServer blade specification 
http://opencompute.org 27 
This primary connector supports two 10G Ethernets, two 1G Ethernets, management 
signals, two serial buses, and management signals.  
The second optional connector supports eight SAS channels for the storage 
expansion connector and signals reserved for an OEM management network.  
The connector is organized as a grid, with rows A through F (three groups: A-C, D-F, 
and G-I) and columns 1 through 6. Note that the columns flip from header to 
receptacle so that the mated pairs match. 
 
Figure 13. AirMax VS pinout arrangement (blade header on left, and backplane receptacle on right) 
 For the 10G Ethernet drivers to operate properly, the controller must be able to 
directly read the serial electrically erasable programmable read-only memory 
(EEPROM) on the 10G SFP+ cables. Serial data (SDA) signals and serial clock (SCK) 
signals are driven from the blade for each small form-factor pluggable + (SFP+) 
connector because the EEPROMs located on the SFP+ cables are hard-wired to 
address 0x0. 
7.2.2 Signal Definitions 
Table 12 below shows the pin definitions for the primary connector (Ethernet) J22. 
Table 12. Primary Connector (Ethernet) J22 
Signal Ball 
pin # 
Pin 
type Description Use 
ENET1G_1_MDI0P A1 I/O 
1GbE MDI lane  
1Gb from NIC to 1G Base-T 
(unused) ENET1G_1_MDI0N B1 I/O 


 
28 January 28, 2014 
Signal Ball 
pin # 
Pin 
type Description Use 
GND C1       
ENET10G_1_RDP D1 O 
10GbE Receive lane 10Gb from SFP+ to NIC 
ENET10G_1_RDN E1 O 
GND F1       
ENET10G_1_TDP G1 I 
10GbE Transmit lane 10Gb from NIC to SFP+ 
ENET10G_1_TDN H1 I 
GND I1       
GND A2       
ENET1G_1_MDI2P B2 I/O 
1GbE MDI lane 
1Gb from NIC to 1G Base-T 
(unused) ENET1G_1_MDI2N C2 I/O 
GND D2 O     
ENET1G_1_MDI1P E2 I/O 
1GbE MDI lane 
1Gb from NIC to 1G Base-T 
(unused) ENET1G_1_MDI1N F2 I/O 
GND G2       
BLADE_EN1 H2 O Node1 Enable for blade Two nodes per sled 
SFP1_PRESENT_N I2 O 
Indicates SFP+ cable is 
present 
Pullup on blade 
ENET1G_1_MDI3P A3 I/O 
1GbE MDI lane 
1Gb from NIC to 1G Base-T 
(unused) ENET1G_1_MDI3N B3 I/O 
GND C3       
SFP1_I2C_DATA1 D3 I/O 
I2C for SFP+ connector Pullups on blade 
SFP1_I2C_CLK1 E3 I 
TRAY_BP_SKU_ID0 F3 O SKU ID Bit for tray backplane Pullup/pulldown on tray BP 
NODE0_RXD G3 I UART for CM communication   



Open Compute Project  Open CloudServer blade specification 
http://opencompute.org 29 
Signal Ball 
pin # 
Pin 
type Description Use 
NODE0_TXD H3 O 
SFP_P3V3 I3 I 3.3V power for SFP+ cables 3.3V Power for SFP+ cables 
GND A4       
ENET1G_2_MDI0P B4 I 
1GbE MDI lane 
1Gb from NIC to 1G Base-T 
(unused) ENET1G_2_MDI0N C4 I 
GND D4       
SFP2_I2C_DATA2 E4 I 
I2C for SFP+ connector Pullups on blade 
SFP2_I2C_CLK2 F4   
NODE1_RXD G4   
1GbE MDI lane 1GbE MDI Lane 
NODE1_TXD H4   
TRAY_BP_SKU_ID1 I4   SKU bit for tray backplane Pullup/Pulldown on tray BP 
ENET1G_2_MDI1P A5 G 
1GbE MDI lane 
1Gb from NIC to 1G Base-T 
(unused) ENET1G_2_MDI1N B5 G 
GND C5 G     
ENET1G_2_MDI2P D5 G 
1GbE MDI lane 
1Gb from NIC to 1G Base-T 
(unused) ENET1G_2_MDI2N E5 G 
GND F5 G     
BLADE_EN2 G5 G Node2 Enable for blade Two nodes per sled 
SFP2_PRESENT_N H5 G 
Indicates SFP+ cable is 
present 
Pullup on blade 
BLADE1_MATED_N I5 G 
Indicates connectors are 
mated 
Pullup on blade 
GND A6 G     
ENET1G_2_MDI3P B6 G 
1GbE MDI lane 
1Gb from NIC to 1G Base-T 
(unused) ENET1G_2_MDI3N C6 G 



 
30 January 28, 2014 
Signal Ball 
pin # 
Pin 
type Description Use 
GND D6 G     
ENET10G_2_RDP E6 G 
10GbE Receive lane 10Gb RX from SFP+ to NIC 
ENET10G_2_RDN F6 G 
GND G6 G     
ENET10G_2_TDP H6 G 
10GbE Transmit lane 10GB TX from NIC to SFP+ 
ENET10G_2_TDN I6 G 
 
Table 13 shows the pin definitions for the secondary connector (SAS) J8. 
Table 13. Pin Definition for Secondary Connector (SAS) J8  
Signal Ball pin # Pin type Sch name  Description Use 
SAS Interface 
SAS_BLAD1_RX1_P D1 O SAS_MEZZ_RX1_C_P 
8 lanes of SAS 
differential 
receive 
Connect to 
SAS Mezz 
conn with 
0.01uF CAP  
SAS_BLAD1_RX2_P H2 O SAS_MEZZ_RX2_C_P 
SAS_BLAD1_RX3_P B2 O SAS_MEZZ_RX3_C_P 
SAS_BLAD1_RX4_P D3 O SAS_MEZZ_RX4_C_P 
SAS_BLAD1_RX5_P H4 O SAS_MEZZ_RX5_C_P 
SAS_BLAD1_RX6_P D5 O SAS_MEZZ_RX6_C_P 
SAS_BLAD1_RX8_P B6 O SAS_MEZZ_RX8_C_P 
SAS_BLAD1_RX7_P H6 O SAS_MEZZ_RX7_C_P 
SAS_BLAD1_RX1_N E1 O SAS_MEZZ_RX1_C_N 
SAS_BLAD1_RX2_N I2 O SAS_MEZZ_RX2_C_N 
SAS_BLAD1_RX3_N C2 O SAS_MEZZ_RX3_C_N 
SAS_BLAD1_RX4_N E3 O SAS_MEZZ_RX4_C_N 



Open Compute Project  Open CloudServer blade specification 
http://opencompute.org 31 
Signal Ball pin # Pin type Sch name  Description Use 
SAS_BLAD1_RX5_N I4 O SAS_MEZZ_RX5_C_N 
SAS_BLAD1_RX6_N E5 O SAS_MEZZ_RX6_C_N 
SAS_BLAD1_RX8_N C6 O SAS_MEZZ_RX8_C_N 
SAS_BLAD1_RX7_N I6 O SAS_MEZZ_RX7_C_N 
SAS_BLAD1_TX2_P G1 I SAS_MEZZ_TX2_P 
8 lanes of SAS 
differential 
transmit 
Connect to 
SAS Mezz 
conn  
SAS_BLAD1_TX1_P A1 I SAS_MEZZ_TX1_P 
SAS_BLAD1_TX3_P E2 I SAS_MEZZ_TX3_P 
SAS_BLAD1_TX4_P G3 I SAS_MEZZ_TX4_P 
SAS_BLAD1_TX5_P E4 I SAS_MEZZ_TX5_P 
SAS_BLAD1_TX6_P A5 I SAS_MEZZ_TX6_P 
SAS_BLAD1_TX7_P G5 I SAS_MEZZ_TX7_P 
SAS_BLAD1_TX8_P E6 I SAS_MEZZ_TX8_P 
SAS_BLAD1_TX2_N H1 I SAS_MEZZ_TX2_N 
SAS_BLAD1_TX1_N B1 I SAS_MEZZ_TX1_N 
SAS_BLAD1_TX3_N F2 I SAS_MEZZ_TX3_N 
SAS_BLAD1_TX4_N H3 I SAS_MEZZ_TX4_N 
SAS_BLAD1_TX5_N F4 I SAS_MEZZ_TX5_N 
SAS_BLAD1_TX6_N B5 I SAS_MEZZ_TX6_N 
SAS_BLAD1_TX7_N H5 I SAS_MEZZ_TX7_N 
SAS_BLAD1_TX8_N F6 I SAS_MEZZ_TX8_N 
AIRMAX_RSVD3 A3   TP  Reserved 
TP 
AIRMAX_RSVD4 B3   TP  Reserved 



 
32 January 28, 2014 
Signal Ball pin # Pin type Sch name  Description Use 
AIRMAX_RSVD1 B4   TP  Reserved 
AIRMAX_RSVD2 C4   TP  Reserved 
Power and ground 
GND C1 G Gnd 
Gnd Gnd 
GND F1 G Gnd 
GND I1 G Gnd 
GND A2 G Gnd 
GND D2 G Gnd 
GND G2 G Gnd 
GND C3 G Gnd 
GND F3 G Gnd 
GND I3 G Gnd 
GND A4 G Gnd 
GND D4 G Gnd 
GND G4 G Gnd 
GND C5 G Gnd 
GND F5 G Gnd 
GND I5 G Gnd 
GND A6 G Gnd 
GND D6 G Gnd 
GND G6 G Gnd 



Open Compute Project  Open CloudServer blade specification 
http://opencompute.org 33 
8 Mezzanine I/O 
The motherboard supports a network mezzanine and a Serial Attach SCSI (SAS) 
mezzanine card. Details, including connector and connector pinouts, are provided in 
the mezzanine NIC and mezzanine SAS specifications. Figure 14 shows a block 
diagram of the mezzanine connections. The mezzanines attach to connectors on the 
tray backplane through the AirMax connectors, as described in Section 7.2 
Motherboard
 Tray
Tray 
Backplane
1200W 
Power
Mgmt
SFP+ #1
300W 12V
Mini-
SAS x4
Airmax
 Mini-
SAS x4
x4
Airmax
10G
SFP+ #2
10G
Network Mezzanine
NWK 1
0
 1
 2
 3
PCIe
NWK 2
0
 1
 2
 3
NC
NC
NC
4 channel 
Retimer
NC
NC
NC
PCI-Express 
Gen3 x8
SAS Mezzanine
SAS
0
 1
 2
 3
 4
 5
 6
 7
CPU
PCI-Express 
Gen3 x8
PCIe
 
Figure 14. Mezzanine I/O 
9 PCI-Express Expansion Slot 
A PCI-Express Gen3 x16 Riser interface is supported on a 164-pin golden finger 
connector.  
Table 14 shows the PCI-Express x16 Riser pin definition. 
 



 
34 January 28, 2014 
 
Table 14. PCI-Express Gen3 x16 Riser Pin Definition 
 
Side B Side A 
1 P12V_BP_PCIE GND 
2 P12V_BP_PCIE P12V_BP_PCIE 
3 P12V_BP_PCIE P12V_BP_PCIE 
4 GND GND 
5 SMB_RSER_R_CLK CLK_100M_SLOTB_DP 
6 SMB_RSER_R_DAT CLK_100M_SLOTB_DN 
7 GND GND 
8 P3V3  
9  PD_SLOT6_JTAG1 P3V3 
10 P3V3_AUX P3V3 
11 IRQ_LVC3_WAKE_N RST_PERST0_N 
12 RISER_TYPE0 GND 
13 GND CLK_100M_SLOTA_DP 
14 P3E_CPU0_SLOT1_TX_C_DP<0> CLK_100M_SLOTA_DN 
15 P3E_CPU0_SLOT1_TX_C_DN<0> GND 
16 GND P3E_CPU0_SLOT1_RX_DP<0> 
17 PCIE_SLOT1_CPRSNT1_N P3E_CPU0_SLOT1_RX_DN<0> 
18 GND GND 
19 P3E_CPU0_SLOT1_TX_C_DP<1> RISER_TYPE1 
20 P3E_CPU0_SLOT1_TX_C_DN<1> GND 
21 GND P3E_CPU0_SLOT1_RX_DP<1> 
22 GND P3E_CPU0_SLOT1_RX_DN<1> 
23 P3E_CPU0_SLOT1_TX_C_DP<2> GND 



Open Compute Project  Open CloudServer blade specification 
http://opencompute.org 35 
 
Side B Side A 
24 P3E_CPU0_SLOT1_TX_C_DN<2> GND 
25 GND P3E_CPU0_SLOT1_RX_DP<2> 
26 GND P3E_CPU0_SLOT1_RX_DN<2> 
27 P3E_CPU0_SLOT1_TX_C_DP<3> GND 
28 P3E_CPU0_SLOT1_TX_C_DN<3> GND 
29 GND P3E_CPU0_SLOT1_RX_DP<3> 
30  P3E_CPU0_SLOT1_RX_DN<3> 
31  GND 
32 GND  
33 P3E_CPU0_SLOT1_TX_C_DP<4>  
34 P3E_CPU0_SLOT1_TX_C_DN<4> GND 
35 GND P3E_CPU0_SLOT1_RX_DP<4> 
36 GND P3E_CPU0_SLOT1_RX_DN<4> 
37 P3E_CPU0_SLOT1_TX_C_DP<5> GND 
38 P3E_CPU0_SLOT1_TX_C_DN<5> GND 
39 GND P3E_CPU0_SLOT1_RX_DP<5> 
40 GND P3E_CPU0_SLOT1_RX_DN<5> 
41 P3E_CPU0_SLOT1_TX_C_DP<6> GND 
42 P3E_CPU0_SLOT1_TX_C_DN<6> GND 
43 GND P3E_CPU0_SLOT1_RX_DP<6> 
44 GND P3E_CPU0_SLOT1_RX_DN<6> 
45 P3E_CPU0_SLOT1_TX_C_DP<7> GND 
46 P3E_CPU0_SLOT1_TX_C_DN<7> GND 
47 GND P3E_CPU0_SLOT1_RX_DP<7> 
48  P3E_CPU0_SLOT1_RX_DN<7> 



 
36 January 28, 2014 
 
Side B Side A 
49 GND GND 
50 P3E_CPU0_SLOT1_TX_C_DP<8>  
51 P3E_CPU0_SLOT1_TX_C_DN<8> GND 
52 GND P3E_CPU0_SLOT1_RX_DP<8> 
53 GND P3E_CPU0_SLOT1_RX_DN<8> 
54 P3E_CPU0_SLOT1_TX_C_DP<9> GND 
55 P3E_CPU0_SLOT1_TX_C_DN<9> GND 
56 GND P3E_CPU0_SLOT1_RX_DP<9> 
57 GND P3E_CPU0_SLOT1_RX_DN<9> 
58 P3E_CPU0_SLOT1_TX_C_DP<10> GND 
59 P3E_CPU0_SLOT1_TX_C_DN<10> GND 
60 GND P3E_CPU0_SLOT1_RX_DP<10> 
61 GND P3E_CPU0_SLOT1_RX_DN<10> 
62 P3E_CPU0_SLOT1_TX_C_DP<11> GND 
63 P3E_CPU0_SLOT1_TX_C_DN<11> GND 
64 GND P3E_CPU0_SLOT1_RX_DP<11> 
65 GND P3E_CPU0_SLOT1_RX_DN<11> 
66 P3E_CPU0_SLOT1_TX_C_DP<12> GND 
67 P3E_CPU0_SLOT1_TX_C_DN<12> GND 
68 GND P3E_CPU0_SLOT1_RX_DP<12> 
69 GND P3E_CPU0_SLOT1_RX_DN<12> 
70 P3E_CPU0_SLOT1_TX_C_DP<13> GND 
71 P3E_CPU0_SLOT1_TX_C_DN<13> GND 
72 GND P3E_CPU0_SLOT1_RX_DP<13> 



Open Compute Project  Open CloudServer blade specification 
http://opencompute.org 37 
 
Side B Side A 
73 GND P3E_CPU0_SLOT1_RX_DN<13> 
74 P3E_CPU0_SLOT1_TX_C_DP<14> GND 
75 P3E_CPU0_SLOT1_TX_C_DN<14> GND 
76 GND P3E_CPU0_SLOT1_RX_DP<14> 
77 GND P3E_CPU0_SLOT1_RX_DN<14> 
78 P3E_CPU0_SLOT1_TX_C_DP<15> GND 
79 P3E_CPU0_SLOT1_TX_C_DN<15> GND 
80 GND P3E_CPU0_SLOT1_RX_DP<15> 
81  P3E_CPU0_SLOT1_RX_DN<15> 
82  GND 
Note that the connector can support two PCIe daughter cards. 
10  Blade Management 
The blade is managed with a customized, low-cost hardware monitoring device 
(HMD), which communicates to the Chassis Manager through a serial port. JBOD 
blades use serial ports already on the chipset for communicating to the Chassis 
Manager.  
10.1 Overview of Blade Management 
Two Blade_Enable signals are provided to the blade, in support of up to two servers 
or devices per blade. Note that the Blade_Enable signals require a complete 
shutdown of power to the server and any associated management hardware. 
There are two dedicated serial links routed to the blade, for use by up to two servers 
or devices per blade. These links use 3.3V. If only one server or device is supported, 
serial port #1 should be used. Both compute and JBOD blades can use the serial link.  
Figure 15 shows a block diagram of the blade, Chassis Manager, and other 
components. 



 
38 January 28, 2014 
  
Figure 15. Server management 
Figure 16 shows details of the blade management hardware. Primary features include: 
 Low pin count (LPC) connection to the chipset to support in-band management 
 Serial numbers, asset information, and event logs stored in electrically erasable 
programmable read-only memory (EEPROM) 
 Thermal sensors for inlet and exhaust  
 Power monitoring through the in-rush controller circuitry 
 Service LEDs 
 Debugging paths for the second Blade_EN signal and serial port  
 
Figure 16. Blade management hardware 
Server Management
Blade
CPU
NIC
Hardware 
Monitoring 
Device
Chassis 
ManagerPCIeIn-Band
ON/OFF
In-Rush
Control
L2 Switch
Out-of-
Band
Blade Management Hardware
Chipset Low End 
BMC
In-Rush Controller Blade_EN[1]
Present
Blade_EN[2]
Serial[1]
Debug UART if available
                    Serial[2]
LPC
EEPROM
i2C /
smbus i2c
Tree
Inlet 
Sensor
Exhaust 
Sensor
GPIO
Power Status 
LED
Front 
Attention LED
Rear  
Attention LED
i2c   power monitor
NWK Mezz



Open Compute Project  Open CloudServer blade specification 
http://opencompute.org 39 
JBOD blades are managed using the Blade_EN signal to the in-rush controller, 
managed using a serial port attached to the SAS fanout expander, and managed in-
band through the operating system. Only the exhaust temperature sensor is required 
because the inlet temperature information can be gathered from the attached server. 
Table 15 lists the blade numbers. 
Table 15. Blade Numbers 
U number Blades when viewed from front Blades when viewed from rear 
12 12 24 24 12 
11 11 23 23 11 
10 10 22 22 10 
9 9 21 21 9 
8 8 20 20 8 
7 7 19 19 7 
6 6 18 18 6 
5 5 17 17 5 
4 4 16 16 4 
3 3 15 15 3 
2 2 14 14 2 
1 1 13 13 1 
10.2 Blade LEDs 
The following sections describe the LEDs used as indicators on the blades and 
chassis. (Also see Section 7.1.3 for information about the in-rush power control 
signals.) 
Each blade has two LEDs: a power status LED that is green/amber and an attention 
LED that is red. Figure 17 shows the location of these LEDs. Because of variations in 
the blade design and functional requirements, the location, visible diameter, and 



 
40 January 28, 2014 
brightness of the LEDs can vary. Additional LEDs can be used to provide more 
information as long as they will not be confused with the required power status and 
attention LEDs.  
 
Figure 17. Locations of blade LEDs 
10.2.1 Blade Power Status LED 
When a blade is first inserted, the LED will turn amber if the backplane has 12V 
power, if the alignment pin is mated, and if the Blade_EN signal is asserted. These 
conditions ensure that the high-speed signal has made connection, and are more 
reliable indicators of proper insertion than simply the 12V power connector.  
When the blade’s management software turns on the primary 12V power, the power 
status LED turns green. Note that the power status LED is driven by an analog 
resistor network tied directly to the power rails, and is not an indication of the health 
of the blade. Table 16 describes the operation of the blade power status LED.   
Table 16. Blade Power Status LED Description 
LED status Condition 
Off 
 Blade is not fully inserted, 12V power is absent, or Blade_EN is de-
asserted 
 Standby and CPU power are off 
Solid Amber ON  Blade is inserted, 12V power is available, and Blade_EN is asserted  
 Standby power is on, but CPU power is off 
Solid Green ON  Standby and CPU power are turned on 


Open Compute Project  Open CloudServer blade specification 
http://opencompute.org 41 
10.2.2 Blade Attention LED 
The blade attention LED directs the service technicians to the blade that requires 
repair. The technician can remove the blade from the rack and replace it with an 
operational blade. When possible, blade diagnostics are used to direct repairs; 
alternately, the scale-out cloud management software can be used. In both cases, 
logs of the repair work are available.  
The attention LED is driven by a single General Purpose I/O (GPIO) bit off the blade’s 
management i2c tree. The attention LED is stateless; when the blade is removed or 
when the Blade_EN signal is de-asserted and turns off the inrush controller power, 
chassis management sends an “off” command to the management subsystem and 
the attention LED is cleared. Table 17 describes the operation of the blade attention 
LED.  
Table 17. Blade Attention LED Description 
LED status Condition 
Off No attention indicated 
Solid RED System needs attention 
If a future blade design supports repair without blade removal (such as hot-swap 
HDDs), the red LED will be used to signal repair. 
Note that a second red LED is located at the rear of the blade so that it is visible 
through the tray when the fan door is opened. This LED is set at the same time as 
the front red attention LED, and indicates which blade needs attention from the rear 
of the chassis.  



 
42 January 28, 2014 
11 Appendix: Commonly Used Acronyms 
This section provides definitions of acronyms used in the system specifications. 
ACPI – advanced configuration and 
power interface  
AHCI – advanced host controller 
interface 
AHJ – authority having jurisdiction 
ANSI – American National 
Standards Institute 
API – application programming 
interface 
ASHRAE – American Society of 
Heating, Refrigerating and Air 
Conditioning Engineers 
ASIC – application-specific 
integrated circuit 
BCD – binary-coded decimal 
BIOS – basic input/output system 
BMC – baseboard management 
controller 
CFM – cubic feet per minute 
(measure of volume flow rate) 
CM – Chassis Manager 
CMOS – complementary metal–
oxide–semiconductor 
COLO – co-location 
CTS – clear to send 
DCMI – Data Center Manageability 
Interface 
DDR3 – double data rate type 3  
DHCP – dynamic host 
configuration protocol 
DIMM – dual inline memory 
module  
DPC - DIMMs per memory channel  
DRAM – dynamic random access 
memory 
DSR – data set ready 
DTR – data terminal ready 
ECC – error-correcting code 
EEPROM - electrically erasable 
programmable read-only memory 
EIA – Electronic Industries Alliance 
EMC – electromagnetic 
compatibility 
EMI – electromagnetic interference 
FRU – field replaceable unit 
FTP – file transfer protocol 
GPIO – general purpose input 
output 
GUID – globally unique identifier 
HBI – high business intelligence 
HCK – Windows Hardware 
Certification Kit 
HMD – hardware monitoring 
device 
HT – hyperthreading 
I2C – inter-integrated circuit 
IBC – international building code 
IDE – integrated development 
environment 



Open Compute Project  Open CloudServer blade specification 
http://opencompute.org 43 
IEC – International Electrotechnical 
Commission 
IOC – I/O controller 
IPMI – intelligent platform 
management interface 
IPsec – IP security 
ITPAC – IT pre-assembled 
components 
JBOD – “just a bunch of disks” 
KCS – keyboard controller style 
L2 – layer 2 
LAN – local area network 
LFF – large form factor 
LPC – low pin count 
LS – least significant 
LUN – logical unit number 
MAC – media access control 
MDC – modular data center 
containers 
MLC – multi-level call 
MTBF – mean time between 
failures  
MUX – multiplexer 
NIC – network interface card 
NUMA – non-uniform memory 
access 
OOB – out of band 
OSHA - Occupational Safety & 
Health Administration 
OTS – off the shelf 
PCB – printed circuit board 
PCIe – peripheral component 
interconnect express 
PCH – platform control hub 
PDB – power distribution 
backplane 
PDU – power distribution unit 
Ph-ph – phase to phase 
Ph-N – phase to neutral 
PNP – plug and play 
POST – power-on self-test 
PSU – power supply unit 
PWM – pulse-width modulation 
PXE – preboot execution 
environment 
QDR – quad data rate 
QFN – quad flat package no-lead 
QPI – Intel QuickPath Interconnect 
QSFP – Quad small form-factor 
pluggable 
RAID – redundant array of 
independent disks 
REST - representational state 
transfer 
RM – Rack Manager 
RMA – remote management agent 
ROC – RAID-on-chip controller 
RSS – receive-side scaling 
RTS – request to send 
RU – rack unit 
RxD – received data 
SAS – serial-attached small 
computer system interface (SCSI) 
SATA – serial AT attachment 
SCK – serial clock 



 
44 January 28, 2014 
SCSI – small computer system 
interface 
SDA – serial data signal 
SDR – sensor data record 
SFF – small form factor 
SFP - small form-factor pluggable  
SMBUS – systems management 
bus 
SMBIOS – systems management 
BIOS 
SOL – serial over LAN 
SPI – serial peripheral interface 
SSD – solid-state drive 
TB – tray backplane 
TDP – thermal design power 
TOR – top of rack 
TPM – trusted platform module 
TxD – transmit data 
U – rack unit 
UART – universal asynchronous 
receiver/transmitter 
UEFI – unified extensible firmware 
interface 
UL – Underwriters Laboratories 
UPS – uninterrupted power supply 
Vpp – voltage peak to peak 
WMI – Windows Management 
Interface 
 